FILE_TYPE = MULTI_PHYS_TABLE;

PART 'OSC4_7X25000018'

{========================================================================================}
:VALUE   | PART_TYPE | MATERIAL | PART_NUMBER    = STANDARD    | LIFECYCLE          | PART_NUMBER   | JEDEC_TYPE | ALT_SYMBOLS | DESCRIPTION                             | MANUFTR | MANUF_PN     | RD_CMPLS_LVL | CMPLS_LVL | CLASS | DIP_SMD | FROM_PJ    | DATA                       | FP_ECN | EE_CHECK_LIST | STATUS | PSL | PREFERENCE | CREATOR | CREATEDAY  ;
{========================================================================================}
 '25MHZ' | 'SMLF'    | 'MISC'   | 'BF625000023'(!) = ''               | ''               | 'BF625000023' |'X_7X'| ''          | 'OSC SMD 25MHZ(+-25PPM,3.3V)7X25000018' | 'TXC'   | '7X25000018' | 'EP(V1)'     | 'EP(V1)'  | 'IO'  | ''      | 'T2R-GAVEN' | 'TXC_7X25000018_revA3.pdf' | ''     | ''            | ''     | ''  | ''         | ''      | '20140704'
 '25MHZ' | 'SMLF'    | 'EMPTY'  | 'BF625000023'(!) = ''               | ''               | 'BF625000023' |'X_7X'| ''          | 'OSC SMD 25MHZ(+-25PPM,3.3V)7X25000018' | 'TXC'   | '7X25000018' | 'EP(V1)'     | 'EP(V1)'  | 'IO'  | ''      | 'T2R-GAVEN' | 'TXC_7X25000018_revA3.pdf' | ''     | ''            | ''     | ''  | ''         | ''      | '20140704'

END_PART

END.

